(kicad_pcb
	(version 20260206)
	(generator "pcbnew")
	(generator_version "10.0")
	(general
		(thickness 1.6)
		(legacy_teardrops no)
	)
	(paper "A4")
	(title_block
		(title "v1-chassis-manager — T6M_CM_d_v01_1031_1645.brd")
		(comment 1 "Open CloudServer (Microsoft) / footprints 1700-1709 of 2512")
	)
	(layers
		(0 "F.Cu" signal "TOP")
		(4 "In1.Cu" signal "GND1")
		(6 "In2.Cu" signal "IN1")
		(8 "In3.Cu" signal "VCC1")
		(10 "In4.Cu" signal "VCC2")
		(12 "In5.Cu" signal "GND2")
		(14 "In6.Cu" signal "IN2")
		(16 "In7.Cu" signal "IN3")
		(18 "In8.Cu" signal "GND3")
		(2 "B.Cu" signal "BOTTOM")
		(9 "F.Adhes" user "F.Adhesive")
		(11 "B.Adhes" user "B.Adhesive")
		(13 "F.Paste" user "Package Geometry/Pastemask Top")
		(15 "B.Paste" user "Package Geometry/Pastemask Bottom")
		(5 "F.SilkS" user "Ref Des/Silkscreen Top")
		(7 "B.SilkS" user "Ref Des/Silkscreen Bottom")
		(1 "F.Mask" user "Board Geometry/Soldermask Top")
		(3 "B.Mask" user "Board Geometry/Soldermask Bottom")
		(17 "Dwgs.User" user "User.Drawings")
		(19 "Cmts.User" user "User.Comments")
		(21 "Eco1.User" user "User.Eco1")
		(23 "Eco2.User" user "User.Eco2")
		(25 "Edge.Cuts" user "Board Geometry/Outline")
		(27 "Margin" user)
		(31 "F.CrtYd" user "Package Geometry/Place Bound Top")
		(29 "B.CrtYd" user "Package Geometry/Place Bound Bottom")
		(35 "F.Fab" user "Ref Des/Assembly Top")
		(33 "B.Fab" user "Ref Des/Assembly Bottom")
	)
	(footprint ""
		(layer "B.Cu")
		(at 167.63238 -150.404322)
		(property "Reference" "C449"
			(at 4.681728 0.013716 0)
			(unlocked yes)
			(layer "B.SilkS")
			(effects
				(font
					(size 0.7874 0.5842)
					(thickness 0.1524)
				)
				(justify left mirror)
			)
		)
		(property "Value" ""
			(at 0 0 0)
			(layer "B.Fab")
			(effects
				(font
					(size 1.27 1.27)
				)
				(justify mirror)
			)
		)
		(duplicate_pad_numbers_are_jumpers no)
		(fp_line
			(start -0.7874 -0.4064)
			(end -0.7874 0.4064)
			(stroke
				(width 0.1524)
				(type default)
			)
			(layer "B.SilkS")
		)
		(fp_line
			(start -0.7874 0.4064)
			(end 0.7874 0.4064)
			(stroke
				(width 0.1524)
				(type default)
			)
			(layer "B.SilkS")
		)
		(fp_line
			(start 0 0.381)
			(end 0 -0.381)
			(stroke
				(width 0.1524)
				(type default)
			)
			(layer "B.SilkS")
		)
		(fp_line
			(start 0.7874 -0.4064)
			(end -0.7874 -0.4064)
			(stroke
				(width 0.1524)
				(type default)
			)
			(layer "B.SilkS")
		)
		(fp_line
			(start 0.7874 0.4064)
			(end 0.7874 -0.4064)
			(stroke
				(width 0.1524)
				(type default)
			)
			(layer "B.SilkS")
		)
		(fp_poly
			(pts
				(xy 0.5334 0.254) (xy 0.635 0.254) (xy 0.635 0.2286) (xy 0.635 -0.254) (xy 0.5334 -0.254) (xy 0.5334 -0.2794)
				(xy -0.5334 -0.2794) (xy -0.5334 -0.254) (xy -0.635 -0.254) (xy -0.635 0.254) (xy -0.5334 0.254)
				(xy -0.5334 0.2794) (xy 0.508 0.2794) (xy 0.5334 0.2794)
			)
			(stroke
				(width 0)
				(type default)
			)
			(fill no)
			(layer "B.CrtYd")
		)
		(pad "1" smd rect
			(at -0.40005 0 180)
			(size 0.4572 0.508)
			(layers "B.Cu" "B.Mask" "B.Paste")
			(net "P1V9_LAN2")
		)
		(pad "2" smd rect
			(at 0.40005 0 180)
			(size 0.4572 0.508)
			(layers "B.Cu" "B.Mask" "B.Paste")
			(net "GND")
		)
	)
	(footprint ""
		(layer "B.Cu")
		(at 129.910586 -170.303952)
		(property "Reference" "R988"
			(at 5.461762 -0.475742 0)
			(unlocked yes)
			(layer "B.SilkS")
			(effects
				(font
					(size 0.7874 0.5842)
					(thickness 0.1524)
				)
				(justify left mirror)
			)
		)
		(property "Value" ""
			(at 0 0 0)
			(layer "B.Fab")
			(effects
				(font
					(size 1.27 1.27)
				)
				(justify mirror)
			)
		)
		(duplicate_pad_numbers_are_jumpers no)
		(fp_line
			(start -0.7874 -0.4064)
			(end -0.7874 0.4064)
			(stroke
				(width 0.1524)
				(type default)
			)
			(layer "B.SilkS")
		)
		(fp_line
			(start -0.7874 0.4064)
			(end 0.7874 0.4064)
			(stroke
				(width 0.1524)
				(type default)
			)
			(layer "B.SilkS")
		)
		(fp_line
			(start 0.7874 -0.4064)
			(end -0.7874 -0.4064)
			(stroke
				(width 0.1524)
				(type default)
			)
			(layer "B.SilkS")
		)
		(fp_line
			(start 0.7874 0.4064)
			(end 0.7874 -0.4064)
			(stroke
				(width 0.1524)
				(type default)
			)
			(layer "B.SilkS")
		)
		(fp_poly
			(pts
				(xy 0.508 0.2794) (xy 0.508 0.2286) (xy 0.635 0.2286) (xy 0.635 -0.254) (xy 0.5334 -0.254) (xy 0.5334 -0.2794)
				(xy -0.5334 -0.2794) (xy -0.5334 -0.254) (xy -0.635 -0.254) (xy -0.635 0.254) (xy -0.5334 0.254)
				(xy -0.5334 0.2794)
			)
			(stroke
				(width 0)
				(type default)
			)
			(fill no)
			(layer "B.CrtYd")
		)
		(pad "1" smd rect
			(at -0.40005 0 180)
			(size 0.4572 0.508)
			(layers "B.Cu" "B.Mask" "B.Paste")
			(net "UART_T8_NODE2_TXD")
		)
		(pad "2" smd rect
			(at 0.40005 0 180)
			(size 0.4572 0.508)
			(layers "B.Cu" "B.Mask" "B.Paste")
			(net "UART_T8_NODE2_TXD_R")
		)
	)
	(footprint ""
		(layer "B.Cu")
		(at 78.83144 -168.441624 180)
		(property "Reference" "R779"
			(at -30.603698 -20.736052 0)
			(unlocked yes)
			(layer "B.SilkS")
			(effects
				(font
					(size 0.7874 0.5842)
					(thickness 0.1524)
				)
				(justify left mirror)
			)
		)
		(property "Value" ""
			(at 0 0 0)
			(layer "B.Fab")
			(effects
				(font
					(size 1.27 1.27)
				)
				(justify mirror)
			)
		)
		(duplicate_pad_numbers_are_jumpers no)
		(fp_line
			(start 0.7874 0.4064)
			(end 0.7874 -0.4064)
			(stroke
				(width 0.1524)
				(type default)
			)
			(layer "B.SilkS")
		)
		(fp_line
			(start 0.7874 -0.4064)
			(end -0.7874 -0.4064)
			(stroke
				(width 0.1524)
				(type default)
			)
			(layer "B.SilkS")
		)
		(fp_line
			(start -0.7874 0.4064)
			(end 0.7874 0.4064)
			(stroke
				(width 0.1524)
				(type default)
			)
			(layer "B.SilkS")
		)
		(fp_line
			(start -0.7874 -0.4064)
			(end -0.7874 0.4064)
			(stroke
				(width 0.1524)
				(type default)
			)
			(layer "B.SilkS")
		)
		(fp_poly
			(pts
				(xy 0.508 0.2794) (xy 0.508 0.2286) (xy 0.635 0.2286) (xy 0.635 -0.254) (xy 0.5334 -0.254) (xy 0.5334 -0.2794)
				(xy -0.5334 -0.2794) (xy -0.5334 -0.254) (xy -0.635 -0.254) (xy -0.635 0.254) (xy -0.5334 0.254)
				(xy -0.5334 0.2794)
			)
			(stroke
				(width 0)
				(type default)
			)
			(fill no)
			(layer "B.CrtYd")
		)
		(pad "1" smd rect
			(at -0.40005 0)
			(size 0.4572 0.508)
			(layers "B.Cu" "B.Mask" "B.Paste")
			(net "CM_CABLE_DET_N")
		)
		(pad "2" smd rect
			(at 0.40005 0)
			(size 0.4572 0.508)
			(layers "B.Cu" "B.Mask" "B.Paste")
			(net "P3V3_NODE1")
		)
	)
	(footprint ""
		(layer "B.Cu")
		(at 58.023506 -72.602852 90)
		(property "Reference" "C43"
			(at -33.175194 -14.611096 270)
			(unlocked yes)
			(layer "B.SilkS")
			(effects
				(font
					(size 0.7874 0.5842)
					(thickness 0.1524)
				)
				(justify left mirror)
			)
		)
		(property "Value" ""
			(at 0 0 90)
			(layer "B.Fab")
			(effects
				(font
					(size 1.27 1.27)
				)
				(justify mirror)
			)
		)
		(duplicate_pad_numbers_are_jumpers no)
		(fp_line
			(start 0.7874 -0.4064)
			(end -0.7874 -0.4064)
			(stroke
				(width 0.1524)
				(type default)
			)
			(layer "B.SilkS")
		)
		(fp_line
			(start -0.7874 -0.4064)
			(end -0.7874 0.4064)
			(stroke
				(width 0.1524)
				(type default)
			)
			(layer "B.SilkS")
		)
		(fp_line
			(start 0 0.381)
			(end 0 -0.381)
			(stroke
				(width 0.1524)
				(type default)
			)
			(layer "B.SilkS")
		)
		(fp_line
			(start 0.7874 0.4064)
			(end 0.7874 -0.4064)
			(stroke
				(width 0.1524)
				(type default)
			)
			(layer "B.SilkS")
		)
		(fp_line
			(start -0.7874 0.4064)
			(end 0.7874 0.4064)
			(stroke
				(width 0.1524)
				(type default)
			)
			(layer "B.SilkS")
		)
		(fp_poly
			(pts
				(xy 0.5334 0.254) (xy 0.635 0.254) (xy 0.635 0.2286) (xy 0.635 -0.254) (xy 0.5334 -0.254) (xy 0.5334 -0.2794)
				(xy -0.5334 -0.2794) (xy -0.5334 -0.254) (xy -0.635 -0.254) (xy -0.635 0.254) (xy -0.5334 0.254)
				(xy -0.5334 0.2794) (xy 0.508 0.2794) (xy 0.5334 0.2794)
			)
			(stroke
				(width 0)
				(type default)
			)
			(fill no)
			(layer "B.CrtYd")
		)
		(pad "1" smd rect
			(at -0.40005 0 270)
			(size 0.4572 0.508)
			(layers "B.Cu" "B.Mask" "B.Paste")
			(net "P1V05_NODE1")
		)
		(pad "2" smd rect
			(at 0.40005 0 270)
			(size 0.4572 0.508)
			(layers "B.Cu" "B.Mask" "B.Paste")
			(net "GND")
		)
	)
	(footprint ""
		(layer "B.Cu")
		(at 182.946294 -159.333692 -90)
		(property "Reference" "C522"
			(at -2.555748 0.166116 270)
			(unlocked yes)
			(layer "B.SilkS")
			(effects
				(font
					(size 0.7874 0.5842)
					(thickness 0.1524)
				)
				(justify left mirror)
			)
		)
		(property "Value" ""
			(at 0 0 90)
			(layer "B.Fab")
			(effects
				(font
					(size 1.27 1.27)
				)
				(justify mirror)
			)
		)
		(duplicate_pad_numbers_are_jumpers no)
		(fp_line
			(start -0.7874 0.406146)
			(end 0.7874 0.406146)
			(stroke
				(width 0.1524)
				(type default)
			)
			(layer "B.SilkS")
		)
		(fp_line
			(start 0.7874 0.406146)
			(end 0.7874 -0.406146)
			(stroke
				(width 0.1524)
				(type default)
			)
			(layer "B.SilkS")
		)
		(fp_line
			(start 0 0.381)
			(end 0 -0.381)
			(stroke
				(width 0.1524)
				(type default)
			)
			(layer "B.SilkS")
		)
		(fp_line
			(start -0.7874 -0.406146)
			(end -0.7874 0.406146)
			(stroke
				(width 0.1524)
				(type default)
			)
			(layer "B.SilkS")
		)
		(fp_line
			(start 0.7874 -0.406146)
			(end -0.7874 -0.406146)
			(stroke
				(width 0.1524)
				(type default)
			)
			(layer "B.SilkS")
		)
		(fp_poly
			(pts
				(xy 0.5334 0.254) (xy 0.635 0.254) (xy 0.635 0.2286) (xy 0.635 -0.254) (xy 0.5334 -0.254) (xy 0.5334 -0.2794)
				(xy -0.5334 -0.2794) (xy -0.5334 -0.254) (xy -0.635 -0.254) (xy -0.635 0.254) (xy -0.5334 0.254)
				(xy -0.5334 0.2794) (xy 0.508 0.2794) (xy 0.5334 0.2794)
			)
			(stroke
				(width 0)
				(type default)
			)
			(fill no)
			(layer "B.CrtYd")
		)
		(pad "1" smd rect
			(at -0.40005 0 90)
			(size 0.4572 0.508)
			(layers "B.Cu" "B.Mask" "B.Paste")
			(net "P1V9_LAN2")
		)
		(pad "2" smd rect
			(at 0.40005 0 90)
			(size 0.4572 0.508)
			(layers "B.Cu" "B.Mask" "B.Paste")
			(net "GND")
		)
	)
	(footprint ""
		(layer "B.Cu")
		(at 143.36776 -187.999624 -90)
		(property "Reference" "C735"
			(at -4.438396 1.753362 270)
			(unlocked yes)
			(layer "B.SilkS")
			(effects
				(font
					(size 0.7874 0.5842)
					(thickness 0.1524)
				)
				(justify left mirror)
			)
		)
		(property "Value" ""
			(at 0 0 90)
			(layer "B.Fab")
			(effects
				(font
					(size 1.27 1.27)
				)
				(justify mirror)
			)
		)
		(duplicate_pad_numbers_are_jumpers no)
		(fp_line
			(start -0.7874 0.4064)
			(end 0.7874 0.4064)
			(stroke
				(width 0.1524)
				(type default)
			)
			(layer "B.SilkS")
		)
		(fp_line
			(start 0.7874 0.4064)
			(end 0.7874 -0.4064)
			(stroke
				(width 0.1524)
				(type default)
			)
			(layer "B.SilkS")
		)
		(fp_line
			(start 0 0.381)
			(end 0 -0.381)
			(stroke
				(width 0.1524)
				(type default)
			)
			(layer "B.SilkS")
		)
		(fp_line
			(start -0.7874 -0.4064)
			(end -0.7874 0.4064)
			(stroke
				(width 0.1524)
				(type default)
			)
			(layer "B.SilkS")
		)
		(fp_line
			(start 0.7874 -0.4064)
			(end -0.7874 -0.4064)
			(stroke
				(width 0.1524)
				(type default)
			)
			(layer "B.SilkS")
		)
		(fp_poly
			(pts
				(xy 0.5334 0.254) (xy 0.635 0.254) (xy 0.635 0.2286) (xy 0.635 -0.254) (xy 0.5334 -0.254) (xy 0.5334 -0.2794)
				(xy -0.5334 -0.2794) (xy -0.5334 -0.254) (xy -0.635 -0.254) (xy -0.635 0.254) (xy -0.5334 0.254)
				(xy -0.5334 0.2794) (xy 0.508 0.2794) (xy 0.5334 0.2794)
			)
			(stroke
				(width 0)
				(type default)
			)
			(fill no)
			(layer "B.CrtYd")
		)
		(pad "1" smd rect
			(at -0.40005 0 90)
			(size 0.4572 0.508)
			(layers "B.Cu" "B.Mask" "B.Paste")
			(net "UART_T11_NODE3_TXD_R")
		)
		(pad "2" smd rect
			(at 0.40005 0 90)
			(size 0.4572 0.508)
			(layers "B.Cu" "B.Mask" "B.Paste")
			(net "GND")
		)
	)
	(footprint ""
		(layer "B.Cu")
		(at 159.62376 -184.949338 90)
		(property "Reference" "R906"
			(at 4.23291 -2.05867 270)
			(unlocked yes)
			(layer "B.SilkS")
			(effects
				(font
					(size 0.7874 0.5842)
					(thickness 0.1524)
				)
				(justify left mirror)
			)
		)
		(property "Value" ""
			(at 0 0 90)
			(layer "B.Fab")
			(effects
				(font
					(size 1.27 1.27)
				)
				(justify mirror)
			)
		)
		(duplicate_pad_numbers_are_jumpers no)
		(fp_line
			(start 0.7874 -0.4064)
			(end -0.7874 -0.4064)
			(stroke
				(width 0.1524)
				(type default)
			)
			(layer "B.SilkS")
		)
		(fp_line
			(start -0.7874 -0.4064)
			(end -0.7874 0.4064)
			(stroke
				(width 0.1524)
				(type default)
			)
			(layer "B.SilkS")
		)
		(fp_line
			(start 0.7874 0.4064)
			(end 0.7874 -0.4064)
			(stroke
				(width 0.1524)
				(type default)
			)
			(layer "B.SilkS")
		)
		(fp_line
			(start -0.7874 0.4064)
			(end 0.7874 0.4064)
			(stroke
				(width 0.1524)
				(type default)
			)
			(layer "B.SilkS")
		)
		(fp_poly
			(pts
				(xy 0.508 0.2794) (xy 0.508 0.2286) (xy 0.635 0.2286) (xy 0.635 -0.254) (xy 0.5334 -0.254) (xy 0.5334 -0.2794)
				(xy -0.5334 -0.2794) (xy -0.5334 -0.254) (xy -0.635 -0.254) (xy -0.635 0.254) (xy -0.5334 0.254)
				(xy -0.5334 0.2794)
			)
			(stroke
				(width 0)
				(type default)
			)
			(fill no)
			(layer "B.CrtYd")
		)
		(pad "1" smd rect
			(at -0.40005 0 270)
			(size 0.4572 0.508)
			(layers "B.Cu" "B.Mask" "B.Paste")
			(net "T12_NODE4_EN")
		)
		(pad "2" smd rect
			(at 0.40005 0 270)
			(size 0.4572 0.508)
			(layers "B.Cu" "B.Mask" "B.Paste")
			(net "T12_NODE4_EN_R")
		)
	)
	(footprint ""
		(layer "B.Cu")
		(at 167.674798 -157.109414)
		(property "Reference" "C457"
			(at 6.03758 -0.088646 0)
			(unlocked yes)
			(layer "B.SilkS")
			(effects
				(font
					(size 0.7874 0.5842)
					(thickness 0.1524)
				)
				(justify left mirror)
			)
		)
		(property "Value" ""
			(at 0 0 0)
			(layer "B.Fab")
			(effects
				(font
					(size 1.27 1.27)
				)
				(justify mirror)
			)
		)
		(duplicate_pad_numbers_are_jumpers no)
		(fp_line
			(start -0.7874 -0.4064)
			(end -0.7874 0.4064)
			(stroke
				(width 0.1524)
				(type default)
			)
			(layer "B.SilkS")
		)
		(fp_line
			(start -0.7874 0.4064)
			(end 0.7874 0.4064)
			(stroke
				(width 0.1524)
				(type default)
			)
			(layer "B.SilkS")
		)
		(fp_line
			(start 0 0.381)
			(end 0 -0.381)
			(stroke
				(width 0.1524)
				(type default)
			)
			(layer "B.SilkS")
		)
		(fp_line
			(start 0.7874 -0.4064)
			(end -0.7874 -0.4064)
			(stroke
				(width 0.1524)
				(type default)
			)
			(layer "B.SilkS")
		)
		(fp_line
			(start 0.7874 0.4064)
			(end 0.7874 -0.4064)
			(stroke
				(width 0.1524)
				(type default)
			)
			(layer "B.SilkS")
		)
		(fp_poly
			(pts
				(xy 0.5334 0.254) (xy 0.635 0.254) (xy 0.635 0.2286) (xy 0.635 -0.254) (xy 0.5334 -0.254) (xy 0.5334 -0.2794)
				(xy -0.5334 -0.2794) (xy -0.5334 -0.254) (xy -0.635 -0.254) (xy -0.635 0.254) (xy -0.5334 0.254)
				(xy -0.5334 0.2794) (xy 0.508 0.2794) (xy 0.5334 0.2794)
			)
			(stroke
				(width 0)
				(type default)
			)
			(fill no)
			(layer "B.CrtYd")
		)
		(pad "1" smd rect
			(at -0.40005 0 180)
			(size 0.4572 0.508)
			(layers "B.Cu" "B.Mask" "B.Paste")
			(net "P1V9_LAN2")
		)
		(pad "2" smd rect
			(at 0.40005 0 180)
			(size 0.4572 0.508)
			(layers "B.Cu" "B.Mask" "B.Paste")
			(net "GND")
		)
	)
	(footprint ""
		(layer "B.Cu")
		(at 110.604554 -64.72555 90)
		(property "Reference" "C182"
			(at -2.854452 0.068072 270)
			(unlocked yes)
			(layer "B.SilkS")
			(effects
				(font
					(size 0.7874 0.5842)
					(thickness 0.1524)
				)
				(justify mirror)
			)
		)
		(property "Value" ""
			(at 0 0 90)
			(layer "B.Fab")
			(effects
				(font
					(size 1.27 1.27)
				)
				(justify mirror)
			)
		)
		(duplicate_pad_numbers_are_jumpers no)
		(fp_line
			(start 1.2954 -0.5842)
			(end -1.2954 -0.5842)
			(stroke
				(width 0.1524)
				(type default)
			)
			(layer "B.SilkS")
		)
		(fp_line
			(start 0 -0.5842)
			(end 0 0.5842)
			(stroke
				(width 0.1524)
				(type default)
			)
			(layer "B.SilkS")
		)
		(fp_line
			(start -1.2954 -0.5842)
			(end -1.2954 0.5842)
			(stroke
				(width 0.1524)
				(type default)
			)
			(layer "B.SilkS")
		)
		(fp_line
			(start 1.2954 0.5842)
			(end 1.2954 -0.5842)
			(stroke
				(width 0.1524)
				(type default)
			)
			(layer "B.SilkS")
		)
		(fp_line
			(start -1.2954 0.5842)
			(end 1.2954 0.5842)
			(stroke
				(width 0.1524)
				(type default)
			)
			(layer "B.SilkS")
		)
		(fp_poly
			(pts
				(xy -0.8636 -0.4572) (xy -0.8636 -0.3556) (xy -1.143 -0.3556) (xy -1.143 0.3556) (xy -0.8636 0.3556)
				(xy -0.8636 0.4572) (xy 0.8636 0.4572) (xy 0.8636 0.3556) (xy 1.143 0.3556) (xy 1.143 -0.3556) (xy 0.8636 -0.3556)
				(xy 0.8636 -0.4572)
			)
			(stroke
				(width 0)
				(type default)
			)
			(fill no)
			(layer "B.CrtYd")
		)
		(fp_line
			(start 0.884936 -0.504952)
			(end -0.884936 -0.504952)
			(stroke
				(width 0.1)
				(type default)
			)
			(layer "B.Fab")
		)
		(fp_line
			(start -0.884936 -0.504952)
			(end -0.884936 0.504952)
			(stroke
				(width 0.1)
				(type default)
			)
			(layer "B.Fab")
		)
		(fp_line
			(start 0.884936 0.504952)
			(end 0.884936 -0.504952)
			(stroke
				(width 0.1)
				(type default)
			)
			(layer "B.Fab")
		)
		(fp_line
			(start -0.884936 0.504952)
			(end 0.884936 0.504952)
			(stroke
				(width 0.1)
				(type default)
			)
			(layer "B.Fab")
		)
		(pad "1" smd rect
			(at -0.7366 0 180)
			(size 0.7112 0.8128)
			(layers "B.Cu" "B.Mask" "B.Paste")
			(net "GND")
		)
		(pad "2" smd rect
			(at 0.7366 0 180)
			(size 0.7112 0.8128)
			(layers "B.Cu" "B.Mask" "B.Paste")
			(net "P1V05_STB_NODE1_XDP_A")
		)
	)
	(footprint ""
		(layer "B.Cu")
		(at 136.50976 -184.951624 90)
		(property "Reference" "R870"
			(at 4.357624 -1.8796 270)
			(unlocked yes)
			(layer "B.SilkS")
			(effects
				(font
					(size 0.7874 0.5842)
					(thickness 0.1524)
				)
				(justify left mirror)
			)
		)
		(property "Value" ""
			(at 0 0 90)
			(layer "B.Fab")
			(effects
				(font
					(size 1.27 1.27)
				)
				(justify mirror)
			)
		)
		(duplicate_pad_numbers_are_jumpers no)
		(fp_line
			(start 0.7874 -0.4064)
			(end -0.7874 -0.4064)
			(stroke
				(width 0.1524)
				(type default)
			)
			(layer "B.SilkS")
		)
		(fp_line
			(start -0.7874 -0.4064)
			(end -0.7874 0.4064)
			(stroke
				(width 0.1524)
				(type default)
			)
			(layer "B.SilkS")
		)
		(fp_line
			(start 0.7874 0.4064)
			(end 0.7874 -0.4064)
			(stroke
				(width 0.1524)
				(type default)
			)
			(layer "B.SilkS")
		)
		(fp_line
			(start -0.7874 0.4064)
			(end 0.7874 0.4064)
			(stroke
				(width 0.1524)
				(type default)
			)
			(layer "B.SilkS")
		)
		(fp_poly
			(pts
				(xy 0.508 0.2794) (xy 0.508 0.2286) (xy 0.635 0.2286) (xy 0.635 -0.254) (xy 0.5334 -0.254) (xy 0.5334 -0.2794)
				(xy -0.5334 -0.2794) (xy -0.5334 -0.254) (xy -0.635 -0.254) (xy -0.635 0.254) (xy -0.5334 0.254)
				(xy -0.5334 0.2794)
			)
			(stroke
				(width 0)
				(type default)
			)
			(fill no)
			(layer "B.CrtYd")
		)
		(pad "1" smd rect
			(at -0.40005 0 270)
			(size 0.4572 0.508)
			(layers "B.Cu" "B.Mask" "B.Paste")
			(net "T9_NODE4_EN")
		)
		(pad "2" smd rect
			(at 0.40005 0 270)
			(size 0.4572 0.508)
			(layers "B.Cu" "B.Mask" "B.Paste")
			(net "T9_NODE4_EN_R")
		)
	)
)
